(kicad_pcb
	(version 20260206)
	(generator "pcbnew")
	(generator_version "10.0")
	(general
		(thickness 1.6)
		(legacy_teardrops no)
	)
	(paper "A4")
	(title_block
		(title "Wiwynn_Tioga_Pass_MB.brd")
		(comment 1 "Tioga Pass / footprints 227-234 of 4770")
	)
	(layers
		(0 "F.Cu" signal "TOP")
		(4 "In1.Cu" signal "L2GND")
		(6 "In2.Cu" signal "L3")
		(8 "In3.Cu" signal "L4GND")
		(10 "In4.Cu" signal "L5")
		(12 "In5.Cu" signal "L6GND")
		(14 "In6.Cu" signal "L7VCC")
		(16 "In7.Cu" signal "L8VCC")
		(18 "In8.Cu" signal "L9GND")
		(20 "In9.Cu" signal "L10")
		(22 "In10.Cu" signal "L11GND")
		(24 "In11.Cu" signal "L12")
		(26 "In12.Cu" signal "L13GND")
		(2 "B.Cu" signal "BOTTOM")
		(9 "F.Adhes" user "F.Adhesive")
		(11 "B.Adhes" user "B.Adhesive")
		(13 "F.Paste" user "Package Geometry/Pastemask Top")
		(15 "B.Paste" user "Package Geometry/Pastemask Bottom")
		(5 "F.SilkS" user "Ref Des/Silkscreen Top")
		(7 "B.SilkS" user "Ref Des/Silkscreen Bottom")
		(1 "F.Mask" user "Board Geometry/Soldermask Top")
		(3 "B.Mask" user "Board Geometry/Soldermask Bottom")
		(17 "Dwgs.User" user "User.Drawings")
		(19 "Cmts.User" user "User.Comments")
		(21 "Eco1.User" user "User.Eco1")
		(23 "Eco2.User" user "User.Eco2")
		(25 "Edge.Cuts" user "Board Geometry/Outline")
		(27 "Margin" user)
		(31 "F.CrtYd" user "Package Geometry/Place Bound Top")
		(29 "B.CrtYd" user "Package Geometry/Place Bound Bottom")
		(35 "F.Fab" user "Ref Des/Assembly Top")
		(33 "B.Fab" user "Ref Des/Assembly Bottom")
	)
	(footprint ""
		(layer "F.Cu")
		(at 27.4828 -81.915 90)
		(property "Reference" "RT14"
			(at 1.01473 0.656336 0)
			(unlocked yes)
			(layer "F.SilkS")
			(effects
				(font
					(size 0.4064 0.254)
					(thickness 0.1524)
				)
			)
		)
		(property "Value" ""
			(at 0 0 90)
			(layer "F.Fab")
			(effects
				(font
					(size 1.27 1.27)
				)
			)
		)
		(duplicate_pad_numbers_are_jumpers no)
		(fp_poly
			(pts
				(xy -0.4953 -0.2032) (xy 0.4953 -0.2032) (xy 0.4953 1.6002) (xy -0.4953 1.6002)
			)
			(stroke
				(width 0)
				(type default)
			)
			(fill no)
			(layer "F.CrtYd")
		)
		(fp_line
			(start 0.4953 -0.2032)
			(end 0.4953 1.6002)
			(stroke
				(width 0.1)
				(type default)
			)
			(layer "F.Fab")
		)
		(fp_line
			(start -0.4953 -0.2032)
			(end 0.4953 -0.2032)
			(stroke
				(width 0.1)
				(type default)
			)
			(layer "F.Fab")
		)
		(fp_line
			(start 0.4953 1.6002)
			(end -0.4953 1.6002)
			(stroke
				(width 0.1)
				(type default)
			)
			(layer "F.Fab")
		)
		(fp_line
			(start -0.4953 1.6002)
			(end -0.4953 -0.2032)
			(stroke
				(width 0.1)
				(type default)
			)
			(layer "F.Fab")
		)
		(pad "1" smd rect
			(at 0 0 90)
			(size 0.762 0.889)
			(layers "F.Cu" "F.Mask" "F.Paste")
			(net "VR_PVCCIN_CPU1_PH4_BOOT")
		)
		(pad "2" smd rect
			(at 0 1.397 90)
			(size 0.762 0.889)
			(layers "F.Cu" "F.Mask" "F.Paste")
			(net "VR_PVCCIN_CPU1_PH4_BOOT_R")
		)
		(zone
			(layer "F.Cu")
			(hatch none 0.5)
			(connect_pads
				(clearance 0)
			)
			(min_thickness 0.25)
			(keepout
				(tracks allowed)
				(vias not_allowed)
				(pads allowed)
				(copperpour not_allowed)
				(footprints allowed)
			)
			(placement
				(enabled no)
				(sheetname "")
			)
			(fill
				(thermal_gap 0.5)
				(thermal_bridge_width 0.5)
				(island_removal_mode 0)
			)
			(polygon
				(pts
					(xy 28.4353 -82.296) (xy 27.9273 -82.296) (xy 27.9273 -81.534) (xy 28.4353 -81.534)
				)
			)
		)
		(zone
			(layer "F.Cu")
			(hatch none 0.5)
			(connect_pads
				(clearance 0)
			)
			(min_thickness 0.25)
			(keepout
				(tracks not_allowed)
				(vias allowed)
				(pads allowed)
				(copperpour not_allowed)
				(footprints allowed)
			)
			(placement
				(enabled no)
				(sheetname "")
			)
			(fill
				(thermal_gap 0.5)
				(thermal_bridge_width 0.5)
				(island_removal_mode 0)
			)
			(polygon
				(pts
					(xy 28.4353 -81.534) (xy 28.4353 -82.296) (xy 27.9273 -82.296) (xy 27.9273 -81.534)
				)
			)
		)
	)
	(footprint ""
		(layer "F.Cu")
		(at 479.2218 -140.8684 90)
		(property "Reference" "U9A4"
			(at 0 0 90)
			(layer "F.SilkS")
			(hide yes)
			(effects
				(font
					(size 1.27 1.27)
				)
			)
		)
		(property "Value" "*"
			(at -2.3622 -8.3185 90)
			(unlocked yes)
			(layer "F.Fab")
			(hide yes)
			(effects
				(font
					(size 1.27 1.016)
					(thickness 0.1524)
				)
			)
		)
		(property "Device Type" "TC7PZ14FU-GP_DISCRET-GA1-TC7PZA"
			(at -2.3622 -10.2235 90)
			(unlocked yes)
			(layer "F.Fab")
			(hide yes)
			(effects
				(font
					(size 1.27 1.016)
					(thickness 0.1524)
				)
			)
		)
		(duplicate_pad_numbers_are_jumpers no)
		(fp_line
			(start 1.4478 -1.7018)
			(end -1.4478 -1.7018)
			(stroke
				(width 0.1524)
				(type default)
			)
			(layer "F.SilkS")
		)
		(fp_line
			(start -1.4478 -1.7018)
			(end -1.4478 1.7018)
			(stroke
				(width 0.1524)
				(type default)
			)
			(layer "F.SilkS")
		)
		(fp_line
			(start 1.4478 1.7018)
			(end 1.4478 -1.7018)
			(stroke
				(width 0.1524)
				(type default)
			)
			(layer "F.SilkS")
		)
		(fp_line
			(start -1.4478 1.7018)
			(end 1.4478 1.7018)
			(stroke
				(width 0.1524)
				(type default)
			)
			(layer "F.SilkS")
		)
		(fp_line
			(start -0.5715 1.7907)
			(end -1.5494 1.7907)
			(stroke
				(width 0.3302)
				(type default)
			)
			(layer "F.SilkS")
		)
		(fp_line
			(start -1.5494 1.7907)
			(end -1.5494 0.8255)
			(stroke
				(width 0.3302)
				(type default)
			)
			(layer "F.SilkS")
		)
		(fp_poly
			(pts
				(xy -0.6604 1.7272) (xy -1.016 2.0828) (xy -0.3048 2.0828)
			)
			(stroke
				(width 0)
				(type default)
			)
			(fill yes)
			(layer "F.SilkS")
		)
		(fp_poly
			(pts
				(xy -1.524 -1.778) (xy 1.524 -1.778) (xy 1.524 1.778) (xy -1.524 1.778)
			)
			(stroke
				(width 0)
				(type default)
			)
			(fill no)
			(layer "F.CrtYd")
		)
		(fp_poly
			(pts
				(xy -1.524 -1.778) (xy 1.524 -1.778) (xy 1.524 1.778) (xy -1.524 1.778)
			)
			(stroke
				(width 0)
				(type default)
			)
			(fill no)
			(layer "F.Fab")
		)
		(pad "1" smd rect
			(at -0.65024 0.9398 90)
			(size 0.4064 1.016)
			(layers "F.Cu" "F.Mask" "F.Paste")
			(net "FP_PWR_BTN_R1_N")
		)
		(pad "2" smd rect
			(at 0 0.9398 90)
			(size 0.4064 1.016)
			(layers "F.Cu" "F.Mask" "F.Paste")
			(net "GND")
		)
		(pad "3" smd rect
			(at 0.65024 0.9398 90)
			(size 0.4064 1.016)
			(layers "F.Cu" "F.Mask" "F.Paste")
			(net "FP_PWR_BTN_BUF1_N")
		)
		(pad "4" smd rect
			(at 0.65024 -0.9398 90)
			(size 0.4064 1.016)
			(layers "F.Cu" "F.Mask" "F.Paste")
			(net "FM_PWR_BTN_R_N")
		)
		(pad "5" smd rect
			(at 0 -0.9398 90)
			(size 0.4064 1.016)
			(layers "F.Cu" "F.Mask" "F.Paste")
			(net "P3V3_STBY")
		)
		(pad "6" smd rect
			(at -0.65024 -0.9398 90)
			(size 0.4064 1.016)
			(layers "F.Cu" "F.Mask" "F.Paste")
			(net "FP_PWR_BTN_BUF1_N")
		)
	)
	(footprint ""
		(layer "F.Cu")
		(at 114.602768 -79.6036 180)
		(property "Reference" "C3D9"
			(at 0 0 180)
			(layer "F.SilkS")
			(hide yes)
			(effects
				(font
					(size 1.27 1.27)
				)
			)
		)
		(property "Value" ""
			(at 0 0 180)
			(layer "F.Fab")
			(effects
				(font
					(size 1.27 1.27)
				)
			)
		)
		(duplicate_pad_numbers_are_jumpers no)
		(fp_poly
			(pts
				(xy -0.4953 -0.2032) (xy 0.4953 -0.2032) (xy 0.4953 1.6002) (xy -0.4953 1.6002)
			)
			(stroke
				(width 0)
				(type default)
			)
			(fill no)
			(layer "F.CrtYd")
		)
		(fp_line
			(start 0.4953 1.6002)
			(end -0.4953 1.6002)
			(stroke
				(width 0.1)
				(type default)
			)
			(layer "F.Fab")
		)
		(fp_line
			(start 0.4953 -0.2032)
			(end 0.4953 1.6002)
			(stroke
				(width 0.1)
				(type default)
			)
			(layer "F.Fab")
		)
		(fp_line
			(start -0.4953 1.6002)
			(end -0.4953 -0.2032)
			(stroke
				(width 0.1)
				(type default)
			)
			(layer "F.Fab")
		)
		(fp_line
			(start -0.4953 -0.2032)
			(end 0.4953 -0.2032)
			(stroke
				(width 0.1)
				(type default)
			)
			(layer "F.Fab")
		)
		(pad "1" smd rect
			(at 0 0 180)
			(size 0.762 0.889)
			(layers "F.Cu" "F.Mask" "F.Paste")
			(net "PVCCIO_CPU1")
		)
		(pad "2" smd rect
			(at 0 1.397 180)
			(size 0.762 0.889)
			(layers "F.Cu" "F.Mask" "F.Paste")
			(net "GND")
		)
		(zone
			(layer "F.Cu")
			(hatch none 0.5)
			(connect_pads
				(clearance 0)
			)
			(min_thickness 0.25)
			(keepout
				(tracks not_allowed)
				(vias allowed)
				(pads allowed)
				(copperpour not_allowed)
				(footprints allowed)
			)
			(placement
				(enabled no)
				(sheetname "")
			)
			(fill
				(thermal_gap 0.5)
				(thermal_bridge_width 0.5)
				(island_removal_mode 0)
			)
			(polygon
				(pts
					(xy 114.983768 -80.0481) (xy 114.221768 -80.0481) (xy 114.221768 -80.5561) (xy 114.983768 -80.5561)
				)
			)
		)
	)
	(footprint ""
		(layer "F.Cu")
		(at 198.44131 -84.847684 90)
		(property "Reference" "C4D11"
			(at 0 0 90)
			(layer "F.SilkS")
			(hide yes)
			(effects
				(font
					(size 1.27 1.27)
				)
			)
		)
		(property "Value" ""
			(at 0 0 90)
			(layer "F.Fab")
			(effects
				(font
					(size 1.27 1.27)
				)
			)
		)
		(duplicate_pad_numbers_are_jumpers no)
		(fp_rect
			(start 0.3048 0.9906)
			(end -0.3048 -0.1016)
			(stroke
				(width 0)
				(type default)
			)
			(fill no)
			(layer "F.CrtYd")
		)
		(fp_line
			(start 0.3048 -0.1016)
			(end -0.3048 -0.1016)
			(stroke
				(width 0.1)
				(type default)
			)
			(layer "F.Fab")
		)
		(fp_line
			(start -0.3048 -0.1016)
			(end -0.3048 0.9906)
			(stroke
				(width 0.1)
				(type default)
			)
			(layer "F.Fab")
		)
		(fp_line
			(start 0.3048 0.9906)
			(end 0.3048 -0.1016)
			(stroke
				(width 0.1)
				(type default)
			)
			(layer "F.Fab")
		)
		(fp_line
			(start -0.3048 0.9906)
			(end 0.3048 0.9906)
			(stroke
				(width 0.1)
				(type default)
			)
			(layer "F.Fab")
		)
		(pad "1" smd rect
			(at 0 0 90)
			(size 0.508 0.508)
			(layers "F.Cu" "F.Mask" "F.Paste")
			(net "VR_FET_SW_P12V_STBY_PVCCIN_CPU0")
		)
		(pad "2" smd rect
			(at 0 0.889 90)
			(size 0.508 0.508)
			(layers "F.Cu" "F.Mask" "F.Paste")
			(net "GND")
		)
		(zone
			(layer "F.Cu")
			(hatch none 0.5)
			(connect_pads
				(clearance 0)
			)
			(min_thickness 0.25)
			(keepout
				(tracks not_allowed)
				(vias allowed)
				(pads allowed)
				(copperpour not_allowed)
				(footprints allowed)
			)
			(placement
				(enabled no)
				(sheetname "")
			)
			(fill
				(thermal_gap 0.5)
				(thermal_bridge_width 0.5)
				(island_removal_mode 0)
			)
			(polygon
				(pts
					(xy 199.07631 -85.101684) (xy 198.69531 -85.101684) (xy 198.69531 -84.593684) (xy 199.07631 -84.593684)
				)
			)
		)
		(zone
			(layer "F.Cu")
			(hatch none 0.5)
			(connect_pads
				(clearance 0)
			)
			(min_thickness 0.25)
			(keepout
				(tracks allowed)
				(vias not_allowed)
				(pads allowed)
				(copperpour not_allowed)
				(footprints allowed)
			)
			(placement
				(enabled no)
				(sheetname "")
			)
			(fill
				(thermal_gap 0.5)
				(thermal_bridge_width 0.5)
				(island_removal_mode 0)
			)
			(polygon
				(pts
					(xy 199.07631 -85.101684) (xy 198.69531 -85.101684) (xy 198.69531 -84.593684) (xy 199.07631 -84.593684)
				)
			)
		)
	)
	(footprint ""
		(layer "F.Cu")
		(at 12.347702 4.098798 -90)
		(property "Reference" "C12W3"
			(at -0.8382 -0.67818 270)
			(unlocked yes)
			(layer "F.SilkS")
			(effects
				(font
					(size 0.4064 0.254)
					(thickness 0.1524)
				)
				(justify left)
			)
		)
		(property "Value" ""
			(at 0 0 270)
			(layer "F.Fab")
			(effects
				(font
					(size 1.27 1.27)
				)
			)
		)
		(duplicate_pad_numbers_are_jumpers no)
		(fp_poly
			(pts
				(xy 0.3048 -0.1016) (xy 0.3048 0.9906) (xy -0.3048 0.9906) (xy -0.3048 -0.1016)
			)
			(stroke
				(width 0)
				(type default)
			)
			(fill no)
			(layer "F.CrtYd")
		)
		(fp_line
			(start -0.3048 0.9906)
			(end 0.3048 0.9906)
			(stroke
				(width 0.1)
				(type default)
			)
			(layer "F.Fab")
		)
		(fp_line
			(start 0.3048 0.9906)
			(end 0.3048 -0.1016)
			(stroke
				(width 0.1)
				(type default)
			)
			(layer "F.Fab")
		)
		(fp_line
			(start -0.3048 -0.1016)
			(end -0.3048 0.9906)
			(stroke
				(width 0.1)
				(type default)
			)
			(layer "F.Fab")
		)
		(fp_line
			(start 0.3048 -0.1016)
			(end -0.3048 -0.1016)
			(stroke
				(width 0.1)
				(type default)
			)
			(layer "F.Fab")
		)
		(pad "1" smd rect
			(at 0 0 270)
			(size 0.508 0.508)
			(layers "F.Cu" "F.Mask" "F.Paste")
			(net "VR_PVDDQ_GHJ_AIINSEN")
		)
		(pad "2" smd rect
			(at 0 0.889 270)
			(size 0.508 0.508)
			(layers "F.Cu" "F.Mask" "F.Paste")
			(net "VR_PVDDQ_GHJ_VINSEN")
		)
		(zone
			(layer "F.Cu")
			(hatch none 0.5)
			(connect_pads
				(clearance 0)
			)
			(min_thickness 0.25)
			(keepout
				(tracks not_allowed)
				(vias allowed)
				(pads allowed)
				(copperpour not_allowed)
				(footprints allowed)
			)
			(placement
				(enabled no)
				(sheetname "")
			)
			(fill
				(thermal_gap 0.5)
				(thermal_bridge_width 0.5)
				(island_removal_mode 0)
			)
			(polygon
				(pts
					(xy 11.712702 3.844798) (xy 11.712702 4.352798) (xy 12.093702 4.352798) (xy 12.093702 3.844798)
				)
			)
		)
		(zone
			(layer "F.Cu")
			(hatch none 0.5)
			(connect_pads
				(clearance 0)
			)
			(min_thickness 0.25)
			(keepout
				(tracks allowed)
				(vias not_allowed)
				(pads allowed)
				(copperpour not_allowed)
				(footprints allowed)
			)
			(placement
				(enabled no)
				(sheetname "")
			)
			(fill
				(thermal_gap 0.5)
				(thermal_bridge_width 0.5)
				(island_removal_mode 0)
			)
			(polygon
				(pts
					(xy 12.093702 3.844798) (xy 12.093702 4.352798) (xy 11.712702 4.352798) (xy 11.712702 3.844798)
				)
			)
		)
	)
	(footprint ""
		(layer "F.Cu")
		(at 188.73978 -72.644 180)
		(property "Reference" "C4D29"
			(at 0 0 180)
			(layer "F.SilkS")
			(hide yes)
			(effects
				(font
					(size 1.27 1.27)
				)
			)
		)
		(property "Value" ""
			(at 0 0 180)
			(layer "F.Fab")
			(effects
				(font
					(size 1.27 1.27)
				)
			)
		)
		(duplicate_pad_numbers_are_jumpers no)
		(fp_rect
			(start 0.3048 -0.1016)
			(end -0.3048 0.9906)
			(stroke
				(width 0)
				(type default)
			)
			(fill no)
			(layer "F.CrtYd")
		)
		(fp_line
			(start 0.3048 0.9906)
			(end 0.3048 -0.1016)
			(stroke
				(width 0.1)
				(type default)
			)
			(layer "F.Fab")
		)
		(fp_line
			(start 0.3048 -0.1016)
			(end -0.3048 -0.1016)
			(stroke
				(width 0.1)
				(type default)
			)
			(layer "F.Fab")
		)
		(fp_line
			(start -0.3048 0.9906)
			(end 0.3048 0.9906)
			(stroke
				(width 0.1)
				(type default)
			)
			(layer "F.Fab")
		)
		(fp_line
			(start -0.3048 -0.1016)
			(end -0.3048 0.9906)
			(stroke
				(width 0.1)
				(type default)
			)
			(layer "F.Fab")
		)
		(pad "1" smd rect
			(at 0 0 180)
			(size 0.508 0.508)
			(layers "F.Cu" "F.Mask" "F.Paste")
			(net "VSENSE_PVSA_CPU0_BVSP")
		)
		(pad "2" smd rect
			(at 0 0.889 180)
			(size 0.508 0.508)
			(layers "F.Cu" "F.Mask" "F.Paste")
			(net "VSENSE_PVSA_CPU0_N")
		)
		(zone
			(layer "F.Cu")
			(hatch none 0.5)
			(connect_pads
				(clearance 0)
			)
			(min_thickness 0.25)
			(keepout
				(tracks allowed)
				(vias not_allowed)
				(pads allowed)
				(copperpour not_allowed)
				(footprints allowed)
			)
			(placement
				(enabled no)
				(sheetname "")
			)
			(fill
				(thermal_gap 0.5)
				(thermal_bridge_width 0.5)
				(island_removal_mode 0)
			)
			(polygon
				(pts
					(xy 188.48578 -72.898) (xy 188.99378 -72.898) (xy 188.99378 -73.279) (xy 188.48578 -73.279)
				)
			)
		)
		(zone
			(layer "F.Cu")
			(hatch none 0.5)
			(connect_pads
				(clearance 0)
			)
			(min_thickness 0.25)
			(keepout
				(tracks not_allowed)
				(vias allowed)
				(pads allowed)
				(copperpour not_allowed)
				(footprints allowed)
			)
			(placement
				(enabled no)
				(sheetname "")
			)
			(fill
				(thermal_gap 0.5)
				(thermal_bridge_width 0.5)
				(island_removal_mode 0)
			)
			(polygon
				(pts
					(xy 188.48578 -72.898) (xy 188.99378 -72.898) (xy 188.99378 -73.279) (xy 188.48578 -73.279)
				)
			)
		)
	)
	(footprint ""
		(layer "F.Cu")
		(at 171.99991 1.999996 90)
		(property "Reference" "TH4G1"
			(at 4.640326 3.13309 0)
			(unlocked yes)
			(layer "F.SilkS")
			(effects
				(font
					(size 0.7874 0.5842)
					(thickness 0.1524)
				)
				(justify left)
			)
		)
		(property "Value" ""
			(at 0 0 90)
			(layer "F.Fab")
			(effects
				(font
					(size 1.27 1.27)
				)
			)
		)
		(duplicate_pad_numbers_are_jumpers no)
		(fp_poly
			(pts
				(arc
					(start 3.0226 0.68834)
					(mid 3.042235 0.827855)
					(end 3.099562 0.956564)
				)
				(arc
					(start 3.099562 0.956564)
					(mid 4.012804 3.550073)
					(end 3.042158 6.12267)
				)
				(arc
					(start 3.042158 6.12267)
					(mid 0 7.518589)
					(end -3.042158 6.12267)
				)
				(arc
					(start -3.042158 6.12267)
					(mid -4.012854 3.55061)
					(end -3.100324 0.957326)
				)
				(arc
					(start -3.100324 0.957326)
					(mid -3.042498 0.827518)
					(end -3.0226 0.686816)
				)
				(arc
					(start -3.0226 -0.000254)
					(mid -2.137121 -2.137227)
					(end 0 -3.022346)
				)
				(arc
					(start 0 -3.022346)
					(mid 2.137227 -2.136973)
					(end 3.0226 0.000254)
				)
			)
			(stroke
				(width 0)
				(type default)
			)
			(fill no)
			(layer "F.CrtYd")
		)
		(pad "1" thru_hole custom
			(at 0 0 90)
			(size 2.00667 2.00667)
			(drill 0.3048)
			(layers "*.Cu" "*.Mask")
			(remove_unused_layers no)
			(net "GND")
			(clearance -0.889)
			(options
				(clearance outline)
				(anchor circle)
			)
			(primitives
				(gr_poly
					(pts
						(arc
							(start 3.042158 3.874516)
							(mid 0 5.270435)
							(end -3.042158 3.874516)
						)
						(arc
							(start -3.042158 3.874516)
							(mid -4.012854 1.302456)
							(end -3.100324 -1.290828)
						)
						(arc
							(start -3.100324 -1.290828)
							(mid -3.042498 -1.420636)
							(end -3.0226 -1.561338)
						)
						(arc
							(start -3.0226 -2.248408)
							(mid -2.137121 -4.385381)
							(end 0 -5.2705)
						)
						(arc
							(start 0 -5.2705)
							(mid 2.137227 -4.385127)
							(end 3.0226 -2.2479)
						)
						(arc
							(start 3.0226 -1.55956)
							(mid 3.04227 -1.420177)
							(end 3.099562 -1.29159)
						)
						(arc
							(start 3.099562 -1.29159)
							(mid 4.012804 1.301919)
							(end 3.042158 3.874516)
						)
					)
					(width 0)
					(fill yes)
				)
			)
		)
	)
	(footprint ""
		(layer "F.Cu")
		(at 352.9838 -30.353)
		(property "Reference" "FB7F1"
			(at 0 0 0)
			(layer "F.SilkS")
			(hide yes)
			(effects
				(font
					(size 1.27 1.27)
				)
			)
		)
		(property "Value" ""
			(at 0 0 0)
			(layer "F.Fab")
			(effects
				(font
					(size 1.27 1.27)
				)
			)
		)
		(duplicate_pad_numbers_are_jumpers no)
		(fp_rect
			(start -0.7239 2.03835)
			(end 0.7239 -0.26035)
			(stroke
				(width 0)
				(type default)
			)
			(fill no)
			(layer "F.CrtYd")
		)
		(fp_line
			(start -0.7239 -0.26035)
			(end 0.7239 -0.26035)
			(stroke
				(width 0.1)
				(type default)
			)
			(layer "F.Fab")
		)
		(fp_line
			(start -0.7239 2.03835)
			(end -0.7239 -0.26035)
			(stroke
				(width 0.1)
				(type default)
			)
			(layer "F.Fab")
		)
		(fp_line
			(start 0.7239 -0.26035)
			(end 0.7239 2.03835)
			(stroke
				(width 0.1)
				(type default)
			)
			(layer "F.Fab")
		)
		(fp_line
			(start 0.7239 2.03835)
			(end -0.7239 2.03835)
			(stroke
				(width 0.1)
				(type default)
			)
			(layer "F.Fab")
		)
		(pad "1" smd rect
			(at 0 0)
			(size 1.27 1.016)
			(layers "F.Cu" "F.Mask" "F.Paste")
			(net "P12V_STBY")
		)
		(pad "2" smd rect
			(at 0 1.778)
			(size 1.27 1.016)
			(layers "F.Cu" "F.Mask" "F.Paste")
			(net "VR_FET_SW_P12V_STBY_PVPP_ABC")
		)
		(zone
			(layer "F.Cu")
			(hatch none 0.5)
			(connect_pads
				(clearance 0)
			)
			(min_thickness 0.25)
			(keepout
				(tracks not_allowed)
				(vias allowed)
				(pads allowed)
				(copperpour not_allowed)
				(footprints allowed)
			)
			(placement
				(enabled no)
				(sheetname "")
			)
			(fill
				(thermal_gap 0.5)
				(thermal_bridge_width 0.5)
				(island_removal_mode 0)
			)
			(polygon
				(pts
					(xy 353.6188 -29.845) (xy 353.6188 -29.083) (xy 353.5299 -29.083) (xy 352.3488 -29.083) (xy 352.3488 -29.845)
				)
			)
		)
	)
)
